# TIMECARD (Time Appliance Project (Time Card)) — schematic netlist excerpt (pin names and nets, part order shuffled) for the footprints in the layout excerpt that follows; sources: Cadence DE-HDL packaged netlist, KiCad conversion of R4006-B0001-02_R01.brd

R82  RESISTOR  33OHM 1%  pkg SMC_0402R_H016  page 21 : \1\ = R_MAC_UART_TX_FPGA_RX ; \2\ = DBG_UART_MAC_TX
C164  CAPACITOR  22UF 10V 20%  pkg SMC_0805R_H057  page 14 : \1\ = XP2R5V_FPGA ; \2\ = SG

(kicad_pcb
	(version 20260206)
	(generator "pcbnew")
	(generator_version "10.0")
	(general
		(thickness 1.6)
		(legacy_teardrops no)
	)
	(paper "A4")
	(title_block
		(title "timecard-production-celestica-r4006 — R4006-B0001-02_R01.brd")
		(comment 1 "Time Appliance Project (Time Card) / footprints 980-981 of 1113")
	)
	(layers
		(0 "F.Cu" signal "TOP")
		(4 "In1.Cu" signal "L02_GND1")
		(6 "In2.Cu" signal "L03_SIG1")
		(8 "In3.Cu" signal "L04_GND2")
		(10 "In4.Cu" signal "L05_VCC1")
		(12 "In5.Cu" signal "L06_VCC2")
		(14 "In6.Cu" signal "L07_GND3")
		(16 "In7.Cu" signal "L08_SIG2")
		(18 "In8.Cu" signal "L09_GND4")
		(2 "B.Cu" signal "BOTTOM")
		(9 "F.Adhes" user "F.Adhesive")
		(11 "B.Adhes" user "B.Adhesive")
		(13 "F.Paste" user "Package Geometry/Pastemask Top")
		(15 "B.Paste" user "Package Geometry/Pastemask Bottom")
		(5 "F.SilkS" user "Ref Des/Silkscreen Top")
		(7 "B.SilkS" user "Ref Des/Silkscreen Bottom")
		(1 "F.Mask" user "Board Geometry/Soldermask Top")
		(3 "B.Mask" user "Board Geometry/Soldermask Bottom")
		(17 "Dwgs.User" user "User.Drawings")
		(19 "Cmts.User" user "User.Comments")
		(21 "Eco1.User" user "User.Eco1")
		(23 "Eco2.User" user "User.Eco2")
		(25 "Edge.Cuts" user "Board Geometry/Outline")
		(27 "Margin" user)
		(31 "F.CrtYd" user "Package Geometry/Place Bound Top")
		(29 "B.CrtYd" user "Package Geometry/Place Bound Bottom")
		(35 "F.Fab" user "Ref Des/Assembly Top")
		(33 "B.Fab" user "Ref Des/Assembly Bottom")
	)
	(footprint ""
		(layer "B.Cu")
		(at 95.631 -26.924 180)
		(property "Reference" "C164"
			(at 0 1.73863 0)
			(unlocked yes)
			(layer "B.SilkS")
			(effects
				(font
					(size 0.7874 0.5842)
					(thickness 0.1524)
				)
				(justify mirror)
			)
		)
		(property "Value" "VAL*"
			(at -0.0762 3.134106 180)
			(unlocked yes)
			(layer "B.Fab")
			(hide yes)
			(effects
				(font
					(size 0.7874 0.5842)
					(thickness 0.1524)
				)
				(justify mirror)
			)
		)
		(property "Device Type" "CAPACITOR-G107-0F226-CM,22UF,2A"
			(at -0.0508 2.194306 180)
			(unlocked yes)
			(layer "B.Fab")
			(hide yes)
			(effects
				(font
					(size 0.7874 0.5842)
					(thickness 0.1524)
				)
				(justify mirror)
			)
		)
		(property "User Part Number" "PARTNUM*"
			(at -0.1016 5.013706 180)
			(unlocked yes)
			(layer "Cmts.User")
			(hide yes)
			(effects
				(font
					(size 0.7874 0.5842)
					(thickness 0.1524)
				)
				(justify mirror)
			)
		)
		(property "Tolerance" "TOL*"
			(at -0.0762 4.048506 180)
			(unlocked yes)
			(layer "Cmts.User")
			(hide yes)
			(effects
				(font
					(size 0.7874 0.5842)
					(thickness 0.1524)
				)
				(justify mirror)
			)
		)
		(duplicate_pad_numbers_are_jumpers no)
		(fp_line
			(start 1.5748 0.9398)
			(end -1.5748 0.9398)
			(stroke
				(width 0.1)
				(type default)
			)
			(layer "B.SilkS")
		)
		(fp_line
			(start 1.5748 -0.9398)
			(end 1.5748 0.9398)
			(stroke
				(width 0.1)
				(type default)
			)
			(layer "B.SilkS")
		)
		(fp_line
			(start -1.5748 0.9398)
			(end -1.5748 -0.9398)
			(stroke
				(width 0.1)
				(type default)
			)
			(layer "B.SilkS")
		)
		(fp_line
			(start -1.5748 -0.9398)
			(end 1.5748 -0.9398)
			(stroke
				(width 0.1)
				(type default)
			)
			(layer "B.SilkS")
		)
		(fp_rect
			(start -1.5748 0.9398)
			(end 1.5748 -0.9398)
			(stroke
				(width 0)
				(type default)
			)
			(fill no)
			(layer "B.CrtYd")
		)
		(fp_line
			(start 1.016 0.635)
			(end -1.016 0.635)
			(stroke
				(width 0.1)
				(type default)
			)
			(layer "B.Fab")
		)
		(fp_line
			(start 1.016 -0.635)
			(end 1.016 0.635)
			(stroke
				(width 0.1)
				(type default)
			)
			(layer "B.Fab")
		)
		(fp_line
			(start -1.016 0.635)
			(end -1.016 -0.635)
			(stroke
				(width 0.1)
				(type default)
			)
			(layer "B.Fab")
		)
		(fp_line
			(start -1.016 -0.635)
			(end 1.016 -0.635)
			(stroke
				(width 0.1)
				(type default)
			)
			(layer "B.Fab")
		)
		(pad "1" smd rect
			(at 0.8382 0)
			(size 0.9652 1.3716)
			(layers "B.Cu" "B.Mask" "B.Paste")
			(net "XP2R5V_FPGA")
		)
		(pad "2" smd rect
			(at -0.8382 0)
			(size 0.9652 1.3716)
			(layers "B.Cu" "B.Mask" "B.Paste")
			(net "SG")
		)
		(zone
			(layer "B.Cu")
			(hatch none 0.5)
			(connect_pads
				(clearance 0)
			)
			(min_thickness 0.25)
			(keepout
				(tracks allowed)
				(vias not_allowed)
				(pads allowed)
				(copperpour not_allowed)
				(footprints allowed)
			)
			(placement
				(enabled no)
				(sheetname "")
			)
			(fill
				(thermal_gap 0.5)
				(thermal_bridge_width 0.5)
				(island_removal_mode 0)
			)
			(polygon
				(pts
					(xy 95.8596 -27.559) (xy 95.4024 -27.559) (xy 95.4024 -26.289) (xy 95.8596 -26.289)
				)
			)
		)
	)
	(footprint ""
		(layer "B.Cu")
		(at 152.781 -70.866)
		(property "Reference" "R82"
			(at 0 -0.97663 0)
			(unlocked yes)
			(layer "B.SilkS")
			(effects
				(font
					(size 0.7874 0.5842)
					(thickness 0.1524)
				)
				(justify mirror)
			)
		)
		(property "Value" "VAL*"
			(at -0.02032 2.13233 0)
			(unlocked yes)
			(layer "B.Fab")
			(hide yes)
			(effects
				(font
					(size 0.7874 0.5842)
					(thickness 0.1524)
				)
				(justify mirror)
			)
		)
		(property "Tolerance" "TOL*"
			(at -0.044704 3.05435 0)
			(unlocked yes)
			(layer "Cmts.User")
			(hide yes)
			(effects
				(font
					(size 0.7874 0.5842)
					(thickness 0.1524)
				)
				(justify mirror)
			)
		)
		(property "User Part Number" "PARTNUM*"
			(at -0.02032 4.024884 0)
			(unlocked yes)
			(layer "Cmts.User")
			(hide yes)
			(effects
				(font
					(size 0.7874 0.5842)
					(thickness 0.1524)
				)
				(justify mirror)
			)
		)
		(property "Device Type" "RESISTOR-G155-133R0-01,33OHM,1%"
			(at -0.008382 1.210564 0)
			(unlocked yes)
			(layer "B.Fab")
			(hide yes)
			(effects
				(font
					(size 0.7874 0.5842)
					(thickness 0.1524)
				)
				(justify mirror)
			)
		)
		(duplicate_pad_numbers_are_jumpers no)
		(fp_line
			(start -1.143 -0.5588)
			(end 1.143 -0.5588)
			(stroke
				(width 0.1)
				(type default)
			)
			(layer "B.SilkS")
		)
		(fp_line
			(start -1.143 0.5588)
			(end -1.143 -0.5588)
			(stroke
				(width 0.1)
				(type default)
			)
			(layer "B.SilkS")
		)
		(fp_line
			(start 1.143 -0.5588)
			(end 1.143 0.5588)
			(stroke
				(width 0.1)
				(type default)
			)
			(layer "B.SilkS")
		)
		(fp_line
			(start 1.143 0.5588)
			(end -1.143 0.5588)
			(stroke
				(width 0.1)
				(type default)
			)
			(layer "B.SilkS")
		)
		(fp_rect
			(start 1.143 0.5588)
			(end -1.143 -0.5588)
			(stroke
				(width 0)
				(type default)
			)
			(fill no)
			(layer "B.CrtYd")
		)
		(fp_line
			(start -0.508 -0.3048)
			(end 0.508 -0.3048)
			(stroke
				(width 0.1)
				(type default)
			)
			(layer "B.Fab")
		)
		(fp_line
			(start -0.508 0.3048)
			(end -0.508 -0.3048)
			(stroke
				(width 0.1)
				(type default)
			)
			(layer "B.Fab")
		)
		(fp_line
			(start 0.508 -0.3048)
			(end 0.508 0.3048)
			(stroke
				(width 0.1)
				(type default)
			)
			(layer "B.Fab")
		)
		(fp_line
			(start 0.508 0.3048)
			(end -0.508 0.3048)
			(stroke
				(width 0.1)
				(type default)
			)
			(layer "B.Fab")
		)
		(pad "1" smd rect
			(at 0.5334 0 180)
			(size 0.7112 0.6096)
			(layers "B.Cu" "B.Mask" "B.Paste")
			(net "R_MAC_UART_TX_FPGA_RX")
		)
		(pad "2" smd rect
			(at -0.5334 0 180)
			(size 0.7112 0.6096)
			(layers "B.Cu" "B.Mask" "B.Paste")
			(net "DBG_UART_MAC_TX")
		)
		(zone
			(layer "B.Cu")
			(hatch none 0.5)
			(connect_pads
				(clearance 0)
			)
			(min_thickness 0.25)
			(keepout
				(tracks allowed)
				(vias not_allowed)
				(pads allowed)
				(copperpour not_allowed)
				(footprints allowed)
			)
			(placement
				(enabled no)
				(sheetname "")
			)
			(fill
				(thermal_gap 0.5)
				(thermal_bridge_width 0.5)
				(island_removal_mode 0)
			)
			(polygon
				(pts
					(xy 152.8572 -70.5612) (xy 152.8572 -71.1708) (xy 152.7048 -71.1708) (xy 152.7048 -70.5612)
				)
			)
		)
	)
)
